FILE_TYPE=LIBRARY_PARTS;
primitive 'PCA9517AD';
  pin
    'ENABLE':
      PIN_NUMBER='(5)';
      BIDIRECTIONAL='TRUE';
      INPUT_LOAD='(-0.01,0.01)';
      OUTPUT_LOAD='(1.0,-1.0)';
    'VCCA':
      PIN_NUMBER='(1)';
      PINUSE='POWER';
    'VCCB':
      PIN_NUMBER='(8)';
      BIDIRECTIONAL='TRUE';
      INPUT_LOAD='(-0.01,0.01)';
      OUTPUT_LOAD='(1.0,-1.0)';
    'SCLA':
      PIN_NUMBER='(2)';
      BIDIRECTIONAL='TRUE';
      INPUT_LOAD='(-0.01,0.01)';
      OUTPUT_LOAD='(1.0,-1.0)';
    'SDAA':
      PIN_NUMBER='(3)';
      BIDIRECTIONAL='TRUE';
      INPUT_LOAD='(-0.01,0.01)';
      OUTPUT_LOAD='(1.0,-1.0)';
    'SDAB':
      PIN_NUMBER='(6)';
      BIDIRECTIONAL='TRUE';
      INPUT_LOAD='(-0.01,0.01)';
      OUTPUT_LOAD='(1.0,-1.0)';
    'SCLB':
      PIN_NUMBER='(7)';
      BIDIRECTIONAL='TRUE';
      INPUT_LOAD='(-0.01,0.01)';
      OUTPUT_LOAD='(1.0,-1.0)';
    'GND':
      PIN_NUMBER='(4)';
      PINUSE='POWER';
  end_pin;
  body
    PART_NAME='PCA9517AD';
    BODY_NAME='PCA9517AD';
    PHYS_DES_PREFIX='U';
    CLASS='DISCRETE';
  end_body;
end_primitive;

END.
